# TIMECARD (Time Appliance Project (Time Card)) — schematic netlist excerpt (pin names and nets, part order shuffled) for the footprints in the layout excerpt that follows; sources: Cadence DE-HDL packaged netlist, KiCad conversion of R4006-B0001-02_R01.brd

C79  CAPACITOR  10UF 25V 20%  pkg SMC_0805R_H057  page 22 : \1\ = XP3R3V_GPS ; \2\ = SG
C224  CAPACITOR  22UF 10V 20%  pkg SMC_0805R_H057  page 31 : \1\ = XP3R3V ; \2\ = SG

(kicad_pcb
	(version 20260206)
	(generator "pcbnew")
	(generator_version "10.0")
	(general
		(thickness 1.6)
		(legacy_teardrops no)
	)
	(paper "A4")
	(title_block
		(title "timecard-production-celestica-r4006 — R4006-B0001-02_R01.brd")
		(comment 1 "Time Appliance Project (Time Card) / footprints 320-322 of 1113")
	)
	(layers
		(0 "F.Cu" signal "TOP")
		(4 "In1.Cu" signal "L02_GND1")
		(6 "In2.Cu" signal "L03_SIG1")
		(8 "In3.Cu" signal "L04_GND2")
		(10 "In4.Cu" signal "L05_VCC1")
		(12 "In5.Cu" signal "L06_VCC2")
		(14 "In6.Cu" signal "L07_GND3")
		(16 "In7.Cu" signal "L08_SIG2")
		(18 "In8.Cu" signal "L09_GND4")
		(2 "B.Cu" signal "BOTTOM")
		(9 "F.Adhes" user "F.Adhesive")
		(11 "B.Adhes" user "B.Adhesive")
		(13 "F.Paste" user "Package Geometry/Pastemask Top")
		(15 "B.Paste" user "Package Geometry/Pastemask Bottom")
		(5 "F.SilkS" user "Ref Des/Silkscreen Top")
		(7 "B.SilkS" user "Ref Des/Silkscreen Bottom")
		(1 "F.Mask" user "Board Geometry/Soldermask Top")
		(3 "B.Mask" user "Board Geometry/Soldermask Bottom")
		(17 "Dwgs.User" user "User.Drawings")
		(19 "Cmts.User" user "User.Comments")
		(21 "Eco1.User" user "User.Eco1")
		(23 "Eco2.User" user "User.Eco2")
		(25 "Edge.Cuts" user "Board Geometry/Outline")
		(27 "Margin" user)
		(31 "F.CrtYd" user "Package Geometry/Place Bound Top")
		(29 "B.CrtYd" user "Package Geometry/Place Bound Bottom")
		(35 "F.Fab" user "Ref Des/Assembly Top")
		(33 "B.Fab" user "Ref Des/Assembly Bottom")
	)
	(footprint ""
		(layer "F.Cu")
		(at 141.605 -24.511 -90)
		(property "Reference" "C224"
			(at -3.556 -0.16637 90)
			(unlocked yes)
			(layer "F.SilkS")
			(effects
				(font
					(size 0.7874 0.5842)
					(thickness 0.1524)
				)
			)
		)
		(property "Value" "VAL*"
			(at 0.0762 3.134106 270)
			(unlocked yes)
			(layer "F.Fab")
			(hide yes)
			(effects
				(font
					(size 0.7874 0.5842)
					(thickness 0.1524)
				)
			)
		)
		(property "Tolerance" "TOL*"
			(at 0.0762 4.048506 270)
			(unlocked yes)
			(layer "Cmts.User")
			(hide yes)
			(effects
				(font
					(size 0.7874 0.5842)
					(thickness 0.1524)
				)
			)
		)
		(property "User Part Number" "PARTNUM*"
			(at 0.1016 5.013706 270)
			(unlocked yes)
			(layer "Cmts.User")
			(hide yes)
			(effects
				(font
					(size 0.7874 0.5842)
					(thickness 0.1524)
				)
			)
		)
		(property "Device Type" "CAPACITOR-G107-0F226-CM,22UF,2A"
			(at 0.0508 2.194306 270)
			(unlocked yes)
			(layer "F.Fab")
			(hide yes)
			(effects
				(font
					(size 0.7874 0.5842)
					(thickness 0.1524)
				)
			)
		)
		(duplicate_pad_numbers_are_jumpers no)
		(fp_line
			(start -1.5748 0.9398)
			(end 1.5748 0.9398)
			(stroke
				(width 0.1)
				(type default)
			)
			(layer "F.SilkS")
		)
		(fp_line
			(start 1.5748 0.9398)
			(end 1.5748 -0.9398)
			(stroke
				(width 0.1)
				(type default)
			)
			(layer "F.SilkS")
		)
		(fp_line
			(start -1.5748 -0.9398)
			(end -1.5748 0.9398)
			(stroke
				(width 0.1)
				(type default)
			)
			(layer "F.SilkS")
		)
		(fp_line
			(start 1.5748 -0.9398)
			(end -1.5748 -0.9398)
			(stroke
				(width 0.1)
				(type default)
			)
			(layer "F.SilkS")
		)
		(fp_rect
			(start -1.5748 -0.9398)
			(end 1.5748 0.9398)
			(stroke
				(width 0)
				(type default)
			)
			(fill no)
			(layer "F.CrtYd")
		)
		(fp_line
			(start -1.016 0.635)
			(end 1.016 0.635)
			(stroke
				(width 0.1)
				(type default)
			)
			(layer "F.Fab")
		)
		(fp_line
			(start 1.016 0.635)
			(end 1.016 -0.635)
			(stroke
				(width 0.1)
				(type default)
			)
			(layer "F.Fab")
		)
		(fp_line
			(start -1.016 -0.635)
			(end -1.016 0.635)
			(stroke
				(width 0.1)
				(type default)
			)
			(layer "F.Fab")
		)
		(fp_line
			(start 1.016 -0.635)
			(end -1.016 -0.635)
			(stroke
				(width 0.1)
				(type default)
			)
			(layer "F.Fab")
		)
		(pad "1" smd rect
			(at -0.8382 0 270)
			(size 0.9652 1.3716)
			(layers "F.Cu" "F.Mask" "F.Paste")
			(net "XP3R3V")
		)
		(pad "2" smd rect
			(at 0.8382 0 270)
			(size 0.9652 1.3716)
			(layers "F.Cu" "F.Mask" "F.Paste")
			(net "SG")
		)
		(zone
			(layer "F.Cu")
			(hatch none 0.5)
			(connect_pads
				(clearance 0)
			)
			(min_thickness 0.25)
			(keepout
				(tracks allowed)
				(vias not_allowed)
				(pads allowed)
				(copperpour not_allowed)
				(footprints allowed)
			)
			(placement
				(enabled no)
				(sheetname "")
			)
			(fill
				(thermal_gap 0.5)
				(thermal_bridge_width 0.5)
				(island_removal_mode 0)
			)
			(polygon
				(pts
					(xy 142.24 -24.7396) (xy 140.97 -24.7396) (xy 140.97 -24.2824) (xy 142.24 -24.2824)
				)
			)
		)
	)
	(footprint ""
		(layer "F.Cu")
		(at 117.3734 -99.7458 180)
		(property "Reference" "C79"
			(at -0.2286 1.68783 0)
			(unlocked yes)
			(layer "F.SilkS")
			(effects
				(font
					(size 0.7874 0.5842)
					(thickness 0.1524)
				)
			)
		)
		(property "Value" "VAL*"
			(at 0.0762 3.134106 180)
			(unlocked yes)
			(layer "F.Fab")
			(hide yes)
			(effects
				(font
					(size 0.7874 0.5842)
					(thickness 0.1524)
				)
			)
		)
		(property "Tolerance" "TOL*"
			(at 0.0762 4.048506 180)
			(unlocked yes)
			(layer "Cmts.User")
			(hide yes)
			(effects
				(font
					(size 0.7874 0.5842)
					(thickness 0.1524)
				)
			)
		)
		(property "User Part Number" "PARTNUM*"
			(at 0.1016 5.013706 180)
			(unlocked yes)
			(layer "Cmts.User")
			(hide yes)
			(effects
				(font
					(size 0.7874 0.5842)
					(thickness 0.1524)
				)
			)
		)
		(property "Device Type" "CAPACITOR-G107-0F106-EM,10UF,2A"
			(at 0.0508 2.194306 180)
			(unlocked yes)
			(layer "F.Fab")
			(hide yes)
			(effects
				(font
					(size 0.7874 0.5842)
					(thickness 0.1524)
				)
			)
		)
		(duplicate_pad_numbers_are_jumpers no)
		(fp_line
			(start 1.5748 0.9398)
			(end 1.5748 -0.9398)
			(stroke
				(width 0.1)
				(type default)
			)
			(layer "F.SilkS")
		)
		(fp_line
			(start 1.5748 -0.9398)
			(end -1.5748 -0.9398)
			(stroke
				(width 0.1)
				(type default)
			)
			(layer "F.SilkS")
		)
		(fp_line
			(start -1.5748 0.9398)
			(end 1.5748 0.9398)
			(stroke
				(width 0.1)
				(type default)
			)
			(layer "F.SilkS")
		)
		(fp_line
			(start -1.5748 -0.9398)
			(end -1.5748 0.9398)
			(stroke
				(width 0.1)
				(type default)
			)
			(layer "F.SilkS")
		)
		(fp_poly
			(pts
				(xy 1.5748 0.9398) (xy -1.5748 0.9398) (xy -1.5748 -0.9398) (xy 1.5748 -0.9398)
			)
			(stroke
				(width 0)
				(type default)
			)
			(fill no)
			(layer "F.CrtYd")
		)
		(fp_line
			(start 1.016 0.635)
			(end 1.016 -0.635)
			(stroke
				(width 0.1)
				(type default)
			)
			(layer "F.Fab")
		)
		(fp_line
			(start 1.016 -0.635)
			(end -1.016 -0.635)
			(stroke
				(width 0.1)
				(type default)
			)
			(layer "F.Fab")
		)
		(fp_line
			(start -1.016 0.635)
			(end 1.016 0.635)
			(stroke
				(width 0.1)
				(type default)
			)
			(layer "F.Fab")
		)
		(fp_line
			(start -1.016 -0.635)
			(end -1.016 0.635)
			(stroke
				(width 0.1)
				(type default)
			)
			(layer "F.Fab")
		)
		(pad "1" smd rect
			(at -0.8382 0 180)
			(size 0.9652 1.3716)
			(layers "F.Cu" "F.Mask" "F.Paste")
			(net "XP3R3V_GPS")
		)
		(pad "2" smd rect
			(at 0.8382 0 180)
			(size 0.9652 1.3716)
			(layers "F.Cu" "F.Mask" "F.Paste")
			(net "SG")
		)
		(zone
			(layer "F.Cu")
			(hatch none 0.5)
			(connect_pads
				(clearance 0)
			)
			(min_thickness 0.25)
			(keepout
				(tracks allowed)
				(vias not_allowed)
				(pads allowed)
				(copperpour not_allowed)
				(footprints allowed)
			)
			(placement
				(enabled no)
				(sheetname "")
			)
			(fill
				(thermal_gap 0.5)
				(thermal_bridge_width 0.5)
				(island_removal_mode 0)
			)
			(polygon
				(pts
					(xy 117.1448 -100.3808) (xy 117.1448 -99.1108) (xy 117.602 -99.1108) (xy 117.602 -100.3808)
				)
			)
		)
	)
	(footprint ""
		(layer "F.Cu")
		(at 57.023 -126.746)
		(property "Reference" "SP80"
			(at 0 0 0)
			(layer "F.SilkS")
			(hide yes)
			(effects
				(font
					(size 1.27 1.27)
				)
			)
		)
		(property "Value" ""
			(at 0 0 0)
			(layer "F.Fab")
			(effects
				(font
					(size 1.27 1.27)
				)
			)
		)
		(duplicate_pad_numbers_are_jumpers no)
	)
)
